# BASEBOARD_FAB2 (Tioga Pass) — schematic netlist excerpt (pin names and nets, part order shuffled) for the footprints in the layout excerpt that follows; sources: Cadence DE-HDL packaged netlist, KiCad conversion of Wiwynn_Tioga_Pass_MB.brd

R6P47  RES  0.0 5% CHIP  pkg 0402  page 204 : A = VR_PVCCIN_CPU0_PH5_VCIN ; B = P5V_STBY
C6R10  CAP  10UF 16V 10% X6S  pkg 0805  page 214 : A = VR_FET_SW_P12V_STBY_PVCCIN_CPU0 ; B = GND
C8P23  CAP  100UF 4V 20% X5R  pkg 0805  page 76 : A = PVCCMCP_CPU1 ; B = GND

(kicad_pcb
	(version 20260206)
	(generator "pcbnew")
	(generator_version "10.0")
	(general
		(thickness 1.6)
		(legacy_teardrops no)
	)
	(paper "A4")
	(title_block
		(title "Wiwynn_Tioga_Pass_MB.brd")
		(comment 1 "Tioga Pass / footprints 2834-2836 of 4770")
	)
	(layers
		(0 "F.Cu" signal "TOP")
		(4 "In1.Cu" signal "L2GND")
		(6 "In2.Cu" signal "L3")
		(8 "In3.Cu" signal "L4GND")
		(10 "In4.Cu" signal "L5")
		(12 "In5.Cu" signal "L6GND")
		(14 "In6.Cu" signal "L7VCC")
		(16 "In7.Cu" signal "L8VCC")
		(18 "In8.Cu" signal "L9GND")
		(20 "In9.Cu" signal "L10")
		(22 "In10.Cu" signal "L11GND")
		(24 "In11.Cu" signal "L12")
		(26 "In12.Cu" signal "L13GND")
		(2 "B.Cu" signal "BOTTOM")
		(9 "F.Adhes" user "F.Adhesive")
		(11 "B.Adhes" user "B.Adhesive")
		(13 "F.Paste" user "Package Geometry/Pastemask Top")
		(15 "B.Paste" user "Package Geometry/Pastemask Bottom")
		(5 "F.SilkS" user "Ref Des/Silkscreen Top")
		(7 "B.SilkS" user "Ref Des/Silkscreen Bottom")
		(1 "F.Mask" user "Board Geometry/Soldermask Top")
		(3 "B.Mask" user "Board Geometry/Soldermask Bottom")
		(17 "Dwgs.User" user "User.Drawings")
		(19 "Cmts.User" user "User.Comments")
		(21 "Eco1.User" user "User.Eco1")
		(23 "Eco2.User" user "User.Eco2")
		(25 "Edge.Cuts" user "Board Geometry/Outline")
		(27 "Margin" user)
		(31 "F.CrtYd" user "Package Geometry/Place Bound Top")
		(29 "B.CrtYd" user "Package Geometry/Place Bound Bottom")
		(35 "F.Fab" user "Ref Des/Assembly Top")
		(33 "B.Fab" user "Ref Des/Assembly Bottom")
	)
	(footprint ""
		(layer "B.Cu")
		(at 104.521254 -73.51014)
		(property "Reference" "C8P23"
			(at 0 0 0)
			(layer "B.SilkS")
			(hide yes)
			(effects
				(font
					(size 1.27 1.27)
				)
				(justify mirror)
			)
		)
		(property "Value" ""
			(at 0 0 0)
			(layer "B.Fab")
			(effects
				(font
					(size 1.27 1.27)
				)
				(justify mirror)
			)
		)
		(duplicate_pad_numbers_are_jumpers no)
		(fp_poly
			(pts
				(xy 0.7239 -0.2159) (xy -0.7239 -0.2159) (xy -0.7239 1.9939) (xy 0.7239 1.9939)
			)
			(stroke
				(width 0)
				(type default)
			)
			(fill no)
			(layer "B.CrtYd")
		)
		(fp_line
			(start -0.7239 -0.2159)
			(end 0.7239 -0.2159)
			(stroke
				(width 0.1)
				(type default)
			)
			(layer "B.Fab")
		)
		(fp_line
			(start -0.7239 1.9939)
			(end -0.7239 -0.2159)
			(stroke
				(width 0.1)
				(type default)
			)
			(layer "B.Fab")
		)
		(fp_line
			(start 0.7239 -0.2159)
			(end 0.7239 1.9939)
			(stroke
				(width 0.1)
				(type default)
			)
			(layer "B.Fab")
		)
		(fp_line
			(start 0.7239 1.9939)
			(end -0.7239 1.9939)
			(stroke
				(width 0.1)
				(type default)
			)
			(layer "B.Fab")
		)
		(pad "1" smd rect
			(at 0 0 180)
			(size 1.27 1.016)
			(layers "B.Cu" "B.Mask" "B.Paste")
			(net "PVCCMCP_CPU1")
		)
		(pad "2" smd rect
			(at 0 1.778 180)
			(size 1.27 1.016)
			(layers "B.Cu" "B.Mask" "B.Paste")
			(net "GND")
		)
		(zone
			(layer "B.Cu")
			(hatch none 0.5)
			(connect_pads
				(clearance 0)
			)
			(min_thickness 0.25)
			(keepout
				(tracks not_allowed)
				(vias allowed)
				(pads allowed)
				(copperpour not_allowed)
				(footprints allowed)
			)
			(placement
				(enabled no)
				(sheetname "")
			)
			(fill
				(thermal_gap 0.5)
				(thermal_bridge_width 0.5)
				(island_removal_mode 0)
			)
			(polygon
				(pts
					(xy 105.156254 -73.00214) (xy 103.886254 -73.00214) (xy 103.886254 -72.24014) (xy 105.156254 -72.24014)
				)
			)
		)
	)
	(footprint ""
		(layer "B.Cu")
		(at 178.562 -53.213 -90)
		(property "Reference" "C6R10"
			(at 0 0 90)
			(layer "B.SilkS")
			(hide yes)
			(effects
				(font
					(size 1.27 1.27)
				)
				(justify mirror)
			)
		)
		(property "Value" ""
			(at 0 0 90)
			(layer "B.Fab")
			(effects
				(font
					(size 1.27 1.27)
				)
				(justify mirror)
			)
		)
		(duplicate_pad_numbers_are_jumpers no)
		(fp_poly
			(pts
				(xy 0.7239 -0.2159) (xy -0.7239 -0.2159) (xy -0.7239 1.9939) (xy 0.7239 1.9939)
			)
			(stroke
				(width 0)
				(type default)
			)
			(fill no)
			(layer "B.CrtYd")
		)
		(fp_line
			(start -0.7239 1.9939)
			(end -0.7239 -0.2159)
			(stroke
				(width 0.1)
				(type default)
			)
			(layer "B.Fab")
		)
		(fp_line
			(start 0.7239 1.9939)
			(end -0.7239 1.9939)
			(stroke
				(width 0.1)
				(type default)
			)
			(layer "B.Fab")
		)
		(fp_line
			(start -0.7239 -0.2159)
			(end 0.7239 -0.2159)
			(stroke
				(width 0.1)
				(type default)
			)
			(layer "B.Fab")
		)
		(fp_line
			(start 0.7239 -0.2159)
			(end 0.7239 1.9939)
			(stroke
				(width 0.1)
				(type default)
			)
			(layer "B.Fab")
		)
		(pad "1" smd rect
			(at 0 0 90)
			(size 1.27 1.016)
			(layers "B.Cu" "B.Mask" "B.Paste")
			(net "VR_FET_SW_P12V_STBY_PVCCIN_CPU0")
		)
		(pad "2" smd rect
			(at 0 1.778 90)
			(size 1.27 1.016)
			(layers "B.Cu" "B.Mask" "B.Paste")
			(net "GND")
		)
		(zone
			(layer "B.Cu")
			(hatch none 0.5)
			(connect_pads
				(clearance 0)
			)
			(min_thickness 0.25)
			(keepout
				(tracks not_allowed)
				(vias allowed)
				(pads allowed)
				(copperpour not_allowed)
				(footprints allowed)
			)
			(placement
				(enabled no)
				(sheetname "")
			)
			(fill
				(thermal_gap 0.5)
				(thermal_bridge_width 0.5)
				(island_removal_mode 0)
			)
			(polygon
				(pts
					(xy 178.054 -52.578) (xy 178.054 -53.848) (xy 177.292 -53.848) (xy 177.292 -52.578)
				)
			)
		)
	)
	(footprint ""
		(layer "B.Cu")
		(at 197.239128 -87.043006 90)
		(property "Reference" "R6P47"
			(at 0 0 90)
			(layer "B.SilkS")
			(hide yes)
			(effects
				(font
					(size 1.27 1.27)
				)
				(justify mirror)
			)
		)
		(property "Value" ""
			(at 0 0 90)
			(layer "B.Fab")
			(effects
				(font
					(size 1.27 1.27)
				)
				(justify mirror)
			)
		)
		(duplicate_pad_numbers_are_jumpers no)
		(fp_rect
			(start 0.2794 -0.1016)
			(end -0.2794 0.9906)
			(stroke
				(width 0)
				(type default)
			)
			(fill no)
			(layer "B.CrtYd")
		)
		(fp_line
			(start 0.2794 -0.1016)
			(end 0.2794 0.9906)
			(stroke
				(width 0.1)
				(type default)
			)
			(layer "B.Fab")
		)
		(fp_line
			(start -0.2794 -0.1016)
			(end 0.2794 -0.1016)
			(stroke
				(width 0.1)
				(type default)
			)
			(layer "B.Fab")
		)
		(fp_line
			(start 0.2794 0.9906)
			(end -0.2794 0.9906)
			(stroke
				(width 0.1)
				(type default)
			)
			(layer "B.Fab")
		)
		(fp_line
			(start -0.2794 0.9906)
			(end -0.2794 -0.1016)
			(stroke
				(width 0.1)
				(type default)
			)
			(layer "B.Fab")
		)
		(pad "1" smd rect
			(at 0 0 270)
			(size 0.508 0.508)
			(layers "B.Cu" "B.Mask" "B.Paste")
			(net "VR_PVCCIN_CPU0_PH5_VCIN")
		)
		(pad "2" smd rect
			(at 0 0.889 270)
			(size 0.508 0.508)
			(layers "B.Cu" "B.Mask" "B.Paste")
			(net "P5V_STBY")
		)
		(zone
			(layer "B.Cu")
			(hatch none 0.5)
			(connect_pads
				(clearance 0)
			)
			(min_thickness 0.25)
			(keepout
				(tracks not_allowed)
				(vias allowed)
				(pads allowed)
				(copperpour not_allowed)
				(footprints allowed)
			)
			(placement
				(enabled no)
				(sheetname "")
			)
			(fill
				(thermal_gap 0.5)
				(thermal_bridge_width 0.5)
				(island_removal_mode 0)
			)
			(polygon
				(pts
					(xy 197.493128 -87.297006) (xy 197.493128 -86.789006) (xy 197.874128 -86.789006) (xy 197.874128 -87.297006)
				)
			)
		)
		(zone
			(layer "B.Cu")
			(hatch none 0.5)
			(connect_pads
				(clearance 0)
			)
			(min_thickness 0.25)
			(keepout
				(tracks allowed)
				(vias not_allowed)
				(pads allowed)
				(copperpour not_allowed)
				(footprints allowed)
			)
			(placement
				(enabled no)
				(sheetname "")
			)
			(fill
				(thermal_gap 0.5)
				(thermal_bridge_width 0.5)
				(island_removal_mode 0)
			)
			(polygon
				(pts
					(xy 197.493128 -87.297006) (xy 197.493128 -86.789006) (xy 197.874128 -86.789006) (xy 197.874128 -87.297006)
				)
			)
		)
	)
)
